(kicad_pcb
	(version 20260206)
	(generator "pcbnew")
	(generator_version "10.0")
	(general
		(thickness 1.6)
		(legacy_teardrops no)
	)
	(paper "A4")
	(title_block
		(title "04192023_DAF0TMB3IC0_F0TG_MB_C_brd_V02_OCP.brd")
		(comment 1 "Grand Teton / footprints 1437-1442 of 8354")
	)
	(layers
		(0 "F.Cu" signal "TOP")
		(4 "In1.Cu" signal "GND")
		(6 "In2.Cu" signal "IN1")
		(8 "In3.Cu" signal "GND1")
		(10 "In4.Cu" signal "IN2")
		(12 "In5.Cu" signal "GND2")
		(14 "In6.Cu" signal "IN3")
		(16 "In7.Cu" signal "GND3")
		(18 "In8.Cu" signal "VCC")
		(20 "In9.Cu" signal "VCC1")
		(22 "In10.Cu" signal "GND4")
		(24 "In11.Cu" signal "IN4")
		(26 "In12.Cu" signal "GND5")
		(28 "In13.Cu" signal "IN5")
		(30 "In14.Cu" signal "GND6")
		(32 "In15.Cu" signal "IN6")
		(34 "In16.Cu" signal "GND7")
		(2 "B.Cu" signal "BOTTOM")
		(9 "F.Adhes" user "F.Adhesive")
		(11 "B.Adhes" user "B.Adhesive")
		(13 "F.Paste" user "Package Geometry/Pastemask Top")
		(15 "B.Paste" user "Package Geometry/Pastemask Bottom")
		(5 "F.SilkS" user "Ref Des/Silkscreen Top")
		(7 "B.SilkS" user "Ref Des/Silkscreen Bottom")
		(1 "F.Mask" user "Board Geometry/Soldermask Top")
		(3 "B.Mask" user "Board Geometry/Soldermask Bottom")
		(17 "Dwgs.User" user "User.Drawings")
		(19 "Cmts.User" user "User.Comments")
		(21 "Eco1.User" user "User.Eco1")
		(23 "Eco2.User" user "User.Eco2")
		(25 "Edge.Cuts" user "Board Geometry/Outline")
		(27 "Margin" user)
		(31 "F.CrtYd" user "Package Geometry/Place Bound Top")
		(29 "B.CrtYd" user "Package Geometry/Place Bound Bottom")
		(35 "F.Fab" user "Ref Des/Assembly Top")
		(33 "B.Fab" user "Ref Des/Assembly Bottom")
	)
	(footprint ""
		(layer "F.Cu")
		(at 437.875172 -28.668218)
		(property "Reference" "R4532"
			(at 0 0 0)
			(layer "F.SilkS")
			(hide yes)
			(effects
				(font
					(size 1.27 1.27)
				)
			)
		)
		(property "Value" ""
			(at 0 0 0)
			(layer "F.Fab")
			(effects
				(font
					(size 1.27 1.27)
				)
			)
		)
		(duplicate_pad_numbers_are_jumpers no)
		(fp_line
			(start -0.7874 -0.4064)
			(end 0.7874 -0.4064)
			(stroke
				(width 0.1524)
				(type default)
			)
			(layer "F.SilkS")
		)
		(fp_line
			(start -0.7874 0.4064)
			(end -0.7874 -0.4064)
			(stroke
				(width 0.1524)
				(type default)
			)
			(layer "F.SilkS")
		)
		(fp_line
			(start 0.7874 -0.4064)
			(end 0.7874 0.4064)
			(stroke
				(width 0.1524)
				(type default)
			)
			(layer "F.SilkS")
		)
		(fp_line
			(start 0.7874 0.4064)
			(end -0.7874 0.4064)
			(stroke
				(width 0.1524)
				(type default)
			)
			(layer "F.SilkS")
		)
		(fp_line
			(start -0.67945 -0.305054)
			(end -0.12065 -0.305054)
			(stroke
				(width 0.1)
				(type default)
			)
			(layer "F.Fab")
		)
		(fp_line
			(start -0.67945 0.3048)
			(end -0.67945 -0.305054)
			(stroke
				(width 0.1)
				(type default)
			)
			(layer "F.Fab")
		)
		(fp_line
			(start -0.12065 -0.305054)
			(end -0.12065 -0.2794)
			(stroke
				(width 0.1)
				(type default)
			)
			(layer "F.Fab")
		)
		(fp_line
			(start -0.12065 -0.2794)
			(end 0.12065 -0.2794)
			(stroke
				(width 0.1)
				(type default)
			)
			(layer "F.Fab")
		)
		(fp_line
			(start -0.12065 0.2794)
			(end -0.12065 0.3048)
			(stroke
				(width 0.1)
				(type default)
			)
			(layer "F.Fab")
		)
		(fp_line
			(start -0.12065 0.3048)
			(end -0.67945 0.3048)
			(stroke
				(width 0.1)
				(type default)
			)
			(layer "F.Fab")
		)
		(fp_line
			(start 0.120396 0.2794)
			(end -0.12065 0.2794)
			(stroke
				(width 0.1)
				(type default)
			)
			(layer "F.Fab")
		)
		(fp_line
			(start 0.120396 0.3048)
			(end 0.120396 0.2794)
			(stroke
				(width 0.1)
				(type default)
			)
			(layer "F.Fab")
		)
		(fp_line
			(start 0.12065 -0.3048)
			(end 0.67945 -0.3048)
			(stroke
				(width 0.1)
				(type default)
			)
			(layer "F.Fab")
		)
		(fp_line
			(start 0.12065 -0.2794)
			(end 0.12065 -0.3048)
			(stroke
				(width 0.1)
				(type default)
			)
			(layer "F.Fab")
		)
		(fp_line
			(start 0.67945 -0.3048)
			(end 0.67945 0.3048)
			(stroke
				(width 0.1)
				(type default)
			)
			(layer "F.Fab")
		)
		(fp_line
			(start 0.67945 0.3048)
			(end 0.120396 0.3048)
			(stroke
				(width 0.1)
				(type default)
			)
			(layer "F.Fab")
		)
		(pad "1" smd circle
			(at -0.40005 0)
			(size 0 0)
			(layers "F.Cu" "F.Mask" "F.Paste")
			(net "P3V3_AUX")
		)
		(pad "2" smd circle
			(at 0.40005 0)
			(size 0 0)
			(layers "F.Cu" "F.Mask" "F.Paste")
			(net "HP_LVC3_OCP_V3_1_P12V_PWRGD")
		)
	)
	(footprint ""
		(layer "F.Cu")
		(at 257.894836 -74.373994 90)
		(property "Reference" "C1592"
			(at 0 0 90)
			(layer "F.SilkS")
			(hide yes)
			(effects
				(font
					(size 1.27 1.27)
				)
			)
		)
		(property "Value" ""
			(at 0 0 90)
			(layer "F.Fab")
			(effects
				(font
					(size 1.27 1.27)
				)
			)
		)
		(duplicate_pad_numbers_are_jumpers no)
		(fp_line
			(start 0.7874 -0.4064)
			(end 0.7874 0.4064)
			(stroke
				(width 0.1524)
				(type default)
			)
			(layer "F.SilkS")
		)
		(fp_line
			(start -0.7874 -0.4064)
			(end 0.7874 -0.4064)
			(stroke
				(width 0.1524)
				(type default)
			)
			(layer "F.SilkS")
		)
		(fp_line
			(start 0.7874 0.4064)
			(end -0.7874 0.4064)
			(stroke
				(width 0.1524)
				(type default)
			)
			(layer "F.SilkS")
		)
		(fp_line
			(start -0.7874 0.4064)
			(end -0.7874 -0.4064)
			(stroke
				(width 0.1524)
				(type default)
			)
			(layer "F.SilkS")
		)
		(fp_line
			(start -0.12065 -0.305054)
			(end -0.12065 -0.2794)
			(stroke
				(width 0.1)
				(type default)
			)
			(layer "F.Fab")
		)
		(fp_line
			(start -0.67945 -0.305054)
			(end -0.12065 -0.305054)
			(stroke
				(width 0.1)
				(type default)
			)
			(layer "F.Fab")
		)
		(fp_line
			(start 0.67945 -0.3048)
			(end 0.67945 0.3048)
			(stroke
				(width 0.1)
				(type default)
			)
			(layer "F.Fab")
		)
		(fp_line
			(start 0.12065 -0.3048)
			(end 0.67945 -0.3048)
			(stroke
				(width 0.1)
				(type default)
			)
			(layer "F.Fab")
		)
		(fp_line
			(start 0.12065 -0.2794)
			(end 0.12065 -0.3048)
			(stroke
				(width 0.1)
				(type default)
			)
			(layer "F.Fab")
		)
		(fp_line
			(start -0.12065 -0.2794)
			(end 0.12065 -0.2794)
			(stroke
				(width 0.1)
				(type default)
			)
			(layer "F.Fab")
		)
		(fp_line
			(start 0.120396 0.2794)
			(end -0.12065 0.2794)
			(stroke
				(width 0.1)
				(type default)
			)
			(layer "F.Fab")
		)
		(fp_line
			(start -0.12065 0.2794)
			(end -0.12065 0.3048)
			(stroke
				(width 0.1)
				(type default)
			)
			(layer "F.Fab")
		)
		(fp_line
			(start 0.67945 0.3048)
			(end 0.120396 0.3048)
			(stroke
				(width 0.1)
				(type default)
			)
			(layer "F.Fab")
		)
		(fp_line
			(start 0.120396 0.3048)
			(end 0.120396 0.2794)
			(stroke
				(width 0.1)
				(type default)
			)
			(layer "F.Fab")
		)
		(fp_line
			(start -0.12065 0.3048)
			(end -0.67945 0.3048)
			(stroke
				(width 0.1)
				(type default)
			)
			(layer "F.Fab")
		)
		(fp_line
			(start -0.67945 0.3048)
			(end -0.67945 -0.305054)
			(stroke
				(width 0.1)
				(type default)
			)
			(layer "F.Fab")
		)
		(pad "1" smd circle
			(at -0.40005 0 90)
			(size 0 0)
			(layers "F.Cu" "F.Mask" "F.Paste")
			(net "P3V3_AUX")
		)
		(pad "2" smd circle
			(at 0.40005 0 90)
			(size 0 0)
			(layers "F.Cu" "F.Mask" "F.Paste")
			(net "GND")
		)
	)
	(footprint ""
		(layer "F.Cu")
		(at 21.176996 -100.54971 180)
		(property "Reference" "R3656"
			(at 0 0 180)
			(layer "F.SilkS")
			(hide yes)
			(effects
				(font
					(size 1.27 1.27)
				)
			)
		)
		(property "Value" ""
			(at 0 0 180)
			(layer "F.Fab")
			(effects
				(font
					(size 1.27 1.27)
				)
			)
		)
		(duplicate_pad_numbers_are_jumpers no)
		(fp_line
			(start 0.7874 0.4064)
			(end -0.7874 0.4064)
			(stroke
				(width 0.1524)
				(type default)
			)
			(layer "F.SilkS")
		)
		(fp_line
			(start 0.7874 -0.4064)
			(end 0.7874 0.4064)
			(stroke
				(width 0.1524)
				(type default)
			)
			(layer "F.SilkS")
		)
		(fp_line
			(start -0.7874 0.4064)
			(end -0.7874 -0.4064)
			(stroke
				(width 0.1524)
				(type default)
			)
			(layer "F.SilkS")
		)
		(fp_line
			(start -0.7874 -0.4064)
			(end 0.7874 -0.4064)
			(stroke
				(width 0.1524)
				(type default)
			)
			(layer "F.SilkS")
		)
		(fp_line
			(start 0.67945 0.3048)
			(end 0.120396 0.3048)
			(stroke
				(width 0.1)
				(type default)
			)
			(layer "F.Fab")
		)
		(fp_line
			(start 0.67945 -0.3048)
			(end 0.67945 0.3048)
			(stroke
				(width 0.1)
				(type default)
			)
			(layer "F.Fab")
		)
		(fp_line
			(start 0.12065 -0.2794)
			(end 0.12065 -0.3048)
			(stroke
				(width 0.1)
				(type default)
			)
			(layer "F.Fab")
		)
		(fp_line
			(start 0.12065 -0.3048)
			(end 0.67945 -0.3048)
			(stroke
				(width 0.1)
				(type default)
			)
			(layer "F.Fab")
		)
		(fp_line
			(start 0.120396 0.3048)
			(end 0.120396 0.2794)
			(stroke
				(width 0.1)
				(type default)
			)
			(layer "F.Fab")
		)
		(fp_line
			(start 0.120396 0.2794)
			(end -0.12065 0.2794)
			(stroke
				(width 0.1)
				(type default)
			)
			(layer "F.Fab")
		)
		(fp_line
			(start -0.12065 0.3048)
			(end -0.67945 0.3048)
			(stroke
				(width 0.1)
				(type default)
			)
			(layer "F.Fab")
		)
		(fp_line
			(start -0.12065 0.2794)
			(end -0.12065 0.3048)
			(stroke
				(width 0.1)
				(type default)
			)
			(layer "F.Fab")
		)
		(fp_line
			(start -0.12065 -0.2794)
			(end 0.12065 -0.2794)
			(stroke
				(width 0.1)
				(type default)
			)
			(layer "F.Fab")
		)
		(fp_line
			(start -0.12065 -0.305054)
			(end -0.12065 -0.2794)
			(stroke
				(width 0.1)
				(type default)
			)
			(layer "F.Fab")
		)
		(fp_line
			(start -0.67945 0.3048)
			(end -0.67945 -0.305054)
			(stroke
				(width 0.1)
				(type default)
			)
			(layer "F.Fab")
		)
		(fp_line
			(start -0.67945 -0.305054)
			(end -0.12065 -0.305054)
			(stroke
				(width 0.1)
				(type default)
			)
			(layer "F.Fab")
		)
		(pad "1" smd circle
			(at -0.40005 0 180)
			(size 0 0)
			(layers "F.Cu" "F.Mask" "F.Paste")
			(net "P3V3_AUX")
		)
		(pad "2" smd circle
			(at 0.40005 0 180)
			(size 0 0)
			(layers "F.Cu" "F.Mask" "F.Paste")
			(net "USB_HUB_OVCUR1")
		)
	)
	(footprint ""
		(layer "F.Cu")
		(at 406.475946 -134.931404 180)
		(property "Reference" "R2343"
			(at 0 0 180)
			(layer "F.SilkS")
			(hide yes)
			(effects
				(font
					(size 1.27 1.27)
				)
			)
		)
		(property "Value" ""
			(at 0 0 180)
			(layer "F.Fab")
			(effects
				(font
					(size 1.27 1.27)
				)
			)
		)
		(duplicate_pad_numbers_are_jumpers no)
		(fp_line
			(start 0.7874 0.4064)
			(end -0.7874 0.4064)
			(stroke
				(width 0.1524)
				(type default)
			)
			(layer "F.SilkS")
		)
		(fp_line
			(start 0.7874 -0.4064)
			(end 0.7874 0.4064)
			(stroke
				(width 0.1524)
				(type default)
			)
			(layer "F.SilkS")
		)
		(fp_line
			(start -0.7874 0.4064)
			(end -0.7874 -0.4064)
			(stroke
				(width 0.1524)
				(type default)
			)
			(layer "F.SilkS")
		)
		(fp_line
			(start -0.7874 -0.4064)
			(end 0.7874 -0.4064)
			(stroke
				(width 0.1524)
				(type default)
			)
			(layer "F.SilkS")
		)
		(fp_line
			(start 0.67945 0.3048)
			(end 0.120396 0.3048)
			(stroke
				(width 0.1)
				(type default)
			)
			(layer "F.Fab")
		)
		(fp_line
			(start 0.67945 -0.3048)
			(end 0.67945 0.3048)
			(stroke
				(width 0.1)
				(type default)
			)
			(layer "F.Fab")
		)
		(fp_line
			(start 0.12065 -0.2794)
			(end 0.12065 -0.3048)
			(stroke
				(width 0.1)
				(type default)
			)
			(layer "F.Fab")
		)
		(fp_line
			(start 0.12065 -0.3048)
			(end 0.67945 -0.3048)
			(stroke
				(width 0.1)
				(type default)
			)
			(layer "F.Fab")
		)
		(fp_line
			(start 0.120396 0.3048)
			(end 0.120396 0.2794)
			(stroke
				(width 0.1)
				(type default)
			)
			(layer "F.Fab")
		)
		(fp_line
			(start 0.120396 0.2794)
			(end -0.12065 0.2794)
			(stroke
				(width 0.1)
				(type default)
			)
			(layer "F.Fab")
		)
		(fp_line
			(start -0.12065 0.3048)
			(end -0.67945 0.3048)
			(stroke
				(width 0.1)
				(type default)
			)
			(layer "F.Fab")
		)
		(fp_line
			(start -0.12065 0.2794)
			(end -0.12065 0.3048)
			(stroke
				(width 0.1)
				(type default)
			)
			(layer "F.Fab")
		)
		(fp_line
			(start -0.12065 -0.2794)
			(end 0.12065 -0.2794)
			(stroke
				(width 0.1)
				(type default)
			)
			(layer "F.Fab")
		)
		(fp_line
			(start -0.12065 -0.305054)
			(end -0.12065 -0.2794)
			(stroke
				(width 0.1)
				(type default)
			)
			(layer "F.Fab")
		)
		(fp_line
			(start -0.67945 0.3048)
			(end -0.67945 -0.305054)
			(stroke
				(width 0.1)
				(type default)
			)
			(layer "F.Fab")
		)
		(fp_line
			(start -0.67945 -0.305054)
			(end -0.12065 -0.305054)
			(stroke
				(width 0.1)
				(type default)
			)
			(layer "F.Fab")
		)
		(pad "1" smd circle
			(at -0.40005 0 180)
			(size 0 0)
			(layers "F.Cu" "F.Mask" "F.Paste")
			(net "P5V_AUX_VCC")
		)
		(pad "2" smd circle
			(at 0.40005 0 180)
			(size 0 0)
			(layers "F.Cu" "F.Mask" "F.Paste")
			(net "PWRGD_P5V_AUX")
		)
	)
	(footprint ""
		(layer "F.Cu")
		(at 152.991312 -26.68778 -90)
		(property "Reference" "R6022"
			(at 0 0 270)
			(layer "F.SilkS")
			(hide yes)
			(effects
				(font
					(size 1.27 1.27)
				)
			)
		)
		(property "Value" ""
			(at 0 0 270)
			(layer "F.Fab")
			(effects
				(font
					(size 1.27 1.27)
				)
			)
		)
		(duplicate_pad_numbers_are_jumpers no)
		(fp_line
			(start -0.7874 0.4064)
			(end -0.7874 -0.4064)
			(stroke
				(width 0.1524)
				(type default)
			)
			(layer "F.SilkS")
		)
		(fp_line
			(start 0.7874 0.4064)
			(end -0.7874 0.4064)
			(stroke
				(width 0.1524)
				(type default)
			)
			(layer "F.SilkS")
		)
		(fp_line
			(start -0.7874 -0.4064)
			(end 0.7874 -0.4064)
			(stroke
				(width 0.1524)
				(type default)
			)
			(layer "F.SilkS")
		)
		(fp_line
			(start 0.7874 -0.4064)
			(end 0.7874 0.4064)
			(stroke
				(width 0.1524)
				(type default)
			)
			(layer "F.SilkS")
		)
		(fp_line
			(start -0.67945 0.3048)
			(end -0.67945 -0.305054)
			(stroke
				(width 0.1)
				(type default)
			)
			(layer "F.Fab")
		)
		(fp_line
			(start -0.12065 0.3048)
			(end -0.67945 0.3048)
			(stroke
				(width 0.1)
				(type default)
			)
			(layer "F.Fab")
		)
		(fp_line
			(start 0.120396 0.3048)
			(end 0.120396 0.2794)
			(stroke
				(width 0.1)
				(type default)
			)
			(layer "F.Fab")
		)
		(fp_line
			(start 0.67945 0.3048)
			(end 0.120396 0.3048)
			(stroke
				(width 0.1)
				(type default)
			)
			(layer "F.Fab")
		)
		(fp_line
			(start -0.12065 0.2794)
			(end -0.12065 0.3048)
			(stroke
				(width 0.1)
				(type default)
			)
			(layer "F.Fab")
		)
		(fp_line
			(start 0.120396 0.2794)
			(end -0.12065 0.2794)
			(stroke
				(width 0.1)
				(type default)
			)
			(layer "F.Fab")
		)
		(fp_line
			(start -0.12065 -0.2794)
			(end 0.12065 -0.2794)
			(stroke
				(width 0.1)
				(type default)
			)
			(layer "F.Fab")
		)
		(fp_line
			(start 0.12065 -0.2794)
			(end 0.12065 -0.3048)
			(stroke
				(width 0.1)
				(type default)
			)
			(layer "F.Fab")
		)
		(fp_line
			(start 0.12065 -0.3048)
			(end 0.67945 -0.3048)
			(stroke
				(width 0.1)
				(type default)
			)
			(layer "F.Fab")
		)
		(fp_line
			(start 0.67945 -0.3048)
			(end 0.67945 0.3048)
			(stroke
				(width 0.1)
				(type default)
			)
			(layer "F.Fab")
		)
		(fp_line
			(start -0.67945 -0.305054)
			(end -0.12065 -0.305054)
			(stroke
				(width 0.1)
				(type default)
			)
			(layer "F.Fab")
		)
		(fp_line
			(start -0.12065 -0.305054)
			(end -0.12065 -0.2794)
			(stroke
				(width 0.1)
				(type default)
			)
			(layer "F.Fab")
		)
		(pad "1" smd circle
			(at -0.40005 0 270)
			(size 0 0)
			(layers "F.Cu" "F.Mask" "F.Paste")
			(net "P3V3_AUX")
		)
		(pad "2" smd circle
			(at 0.40005 0 270)
			(size 0 0)
			(layers "F.Cu" "F.Mask" "F.Paste")
			(net "SGPIO_SCM_DI_<1>")
		)
	)
	(footprint ""
		(layer "F.Cu")
		(at 305.002184 -343.712038 180)
		(property "Reference" "PC191"
			(at 0 0 180)
			(layer "F.SilkS")
			(hide yes)
			(effects
				(font
					(size 1.27 1.27)
				)
			)
		)
		(property "Value" ""
			(at 0 0 180)
			(layer "F.Fab")
			(effects
				(font
					(size 1.27 1.27)
				)
			)
		)
		(duplicate_pad_numbers_are_jumpers no)
		(fp_line
			(start 0.7874 0.4064)
			(end -0.7874 0.4064)
			(stroke
				(width 0.1524)
				(type default)
			)
			(layer "F.SilkS")
		)
		(fp_line
			(start 0.7874 -0.4064)
			(end 0.7874 0.4064)
			(stroke
				(width 0.1524)
				(type default)
			)
			(layer "F.SilkS")
		)
		(fp_line
			(start -0.7874 0.4064)
			(end -0.7874 -0.4064)
			(stroke
				(width 0.1524)
				(type default)
			)
			(layer "F.SilkS")
		)
		(fp_line
			(start -0.7874 -0.4064)
			(end 0.7874 -0.4064)
			(stroke
				(width 0.1524)
				(type default)
			)
			(layer "F.SilkS")
		)
		(fp_line
			(start 0.67945 0.3048)
			(end 0.120396 0.3048)
			(stroke
				(width 0.1)
				(type default)
			)
			(layer "F.Fab")
		)
		(fp_line
			(start 0.67945 -0.3048)
			(end 0.67945 0.3048)
			(stroke
				(width 0.1)
				(type default)
			)
			(layer "F.Fab")
		)
		(fp_line
			(start 0.12065 -0.2794)
			(end 0.12065 -0.3048)
			(stroke
				(width 0.1)
				(type default)
			)
			(layer "F.Fab")
		)
		(fp_line
			(start 0.12065 -0.3048)
			(end 0.67945 -0.3048)
			(stroke
				(width 0.1)
				(type default)
			)
			(layer "F.Fab")
		)
		(fp_line
			(start 0.120396 0.3048)
			(end 0.120396 0.2794)
			(stroke
				(width 0.1)
				(type default)
			)
			(layer "F.Fab")
		)
		(fp_line
			(start 0.120396 0.2794)
			(end -0.12065 0.2794)
			(stroke
				(width 0.1)
				(type default)
			)
			(layer "F.Fab")
		)
		(fp_line
			(start -0.12065 0.3048)
			(end -0.67945 0.3048)
			(stroke
				(width 0.1)
				(type default)
			)
			(layer "F.Fab")
		)
		(fp_line
			(start -0.12065 0.2794)
			(end -0.12065 0.3048)
			(stroke
				(width 0.1)
				(type default)
			)
			(layer "F.Fab")
		)
		(fp_line
			(start -0.12065 -0.2794)
			(end 0.12065 -0.2794)
			(stroke
				(width 0.1)
				(type default)
			)
			(layer "F.Fab")
		)
		(fp_line
			(start -0.12065 -0.305054)
			(end -0.12065 -0.2794)
			(stroke
				(width 0.1)
				(type default)
			)
			(layer "F.Fab")
		)
		(fp_line
			(start -0.67945 0.3048)
			(end -0.67945 -0.305054)
			(stroke
				(width 0.1)
				(type default)
			)
			(layer "F.Fab")
		)
		(fp_line
			(start -0.67945 -0.305054)
			(end -0.12065 -0.305054)
			(stroke
				(width 0.1)
				(type default)
			)
			(layer "F.Fab")
		)
		(pad "1" smd circle
			(at -0.40005 0 180)
			(size 0 0)
			(layers "F.Cu" "F.Mask" "F.Paste")
			(net "SW_PVDDCR_CPU1_P0_SW4")
		)
		(pad "2" smd circle
			(at 0.40005 0 180)
			(size 0 0)
			(layers "F.Cu" "F.Mask" "F.Paste")
			(net "SW_PVDDCR_CPU1_P0_SW4_RC")
		)
	)
)
